(kicad_pcb
	(version 20260206)
	(generator "pcbnew")
	(generator_version "10.0")
	(general
		(thickness 1.6)
		(legacy_teardrops no)
	)
	(paper "A4")
	(title_block
		(title "Wiwynn_Tioga_Pass_MB.brd")
		(comment 1 "Tioga Pass / footprints 3328-3334 of 4770")
	)
	(layers
		(0 "F.Cu" signal "TOP")
		(4 "In1.Cu" signal "L2GND")
		(6 "In2.Cu" signal "L3")
		(8 "In3.Cu" signal "L4GND")
		(10 "In4.Cu" signal "L5")
		(12 "In5.Cu" signal "L6GND")
		(14 "In6.Cu" signal "L7VCC")
		(16 "In7.Cu" signal "L8VCC")
		(18 "In8.Cu" signal "L9GND")
		(20 "In9.Cu" signal "L10")
		(22 "In10.Cu" signal "L11GND")
		(24 "In11.Cu" signal "L12")
		(26 "In12.Cu" signal "L13GND")
		(2 "B.Cu" signal "BOTTOM")
		(9 "F.Adhes" user "F.Adhesive")
		(11 "B.Adhes" user "B.Adhesive")
		(13 "F.Paste" user "Package Geometry/Pastemask Top")
		(15 "B.Paste" user "Package Geometry/Pastemask Bottom")
		(5 "F.SilkS" user "Ref Des/Silkscreen Top")
		(7 "B.SilkS" user "Ref Des/Silkscreen Bottom")
		(1 "F.Mask" user "Board Geometry/Soldermask Top")
		(3 "B.Mask" user "Board Geometry/Soldermask Bottom")
		(17 "Dwgs.User" user "User.Drawings")
		(19 "Cmts.User" user "User.Comments")
		(21 "Eco1.User" user "User.Eco1")
		(23 "Eco2.User" user "User.Eco2")
		(25 "Edge.Cuts" user "Board Geometry/Outline")
		(27 "Margin" user)
		(31 "F.CrtYd" user "Package Geometry/Place Bound Top")
		(29 "B.CrtYd" user "Package Geometry/Place Bound Bottom")
		(35 "F.Fab" user "Ref Des/Assembly Top")
		(33 "B.Fab" user "Ref Des/Assembly Bottom")
	)
	(footprint ""
		(layer "B.Cu")
		(at 162.687 -81.788 90)
		(property "Reference" "R7P4"
			(at 0 0 90)
			(layer "B.SilkS")
			(hide yes)
			(effects
				(font
					(size 1.27 1.27)
				)
				(justify mirror)
			)
		)
		(property "Value" ""
			(at 0 0 90)
			(layer "B.Fab")
			(effects
				(font
					(size 1.27 1.27)
				)
				(justify mirror)
			)
		)
		(duplicate_pad_numbers_are_jumpers no)
		(fp_poly
			(pts
				(xy 0.2794 -0.1016) (xy -0.2794 -0.1016) (xy -0.2794 0.9906) (xy 0.2794 0.9906)
			)
			(stroke
				(width 0)
				(type default)
			)
			(fill no)
			(layer "B.CrtYd")
		)
		(fp_line
			(start 0.2794 -0.1016)
			(end 0.2794 0.9906)
			(stroke
				(width 0.1)
				(type default)
			)
			(layer "B.Fab")
		)
		(fp_line
			(start -0.2794 -0.1016)
			(end 0.2794 -0.1016)
			(stroke
				(width 0.1)
				(type default)
			)
			(layer "B.Fab")
		)
		(fp_line
			(start 0.2794 0.9906)
			(end -0.2794 0.9906)
			(stroke
				(width 0.1)
				(type default)
			)
			(layer "B.Fab")
		)
		(fp_line
			(start -0.2794 0.9906)
			(end -0.2794 -0.1016)
			(stroke
				(width 0.1)
				(type default)
			)
			(layer "B.Fab")
		)
		(pad "1" smd rect
			(at 0 0 270)
			(size 0.508 0.508)
			(layers "B.Cu" "B.Mask" "B.Paste")
			(net "CLK_100M_CPU1_PE_REFCLK_DN")
		)
		(pad "2" smd rect
			(at 0 0.889 270)
			(size 0.508 0.508)
			(layers "B.Cu" "B.Mask" "B.Paste")
			(net "GND")
		)
		(zone
			(layer "B.Cu")
			(hatch none 0.5)
			(connect_pads
				(clearance 0)
			)
			(min_thickness 0.25)
			(keepout
				(tracks allowed)
				(vias not_allowed)
				(pads allowed)
				(copperpour not_allowed)
				(footprints allowed)
			)
			(placement
				(enabled no)
				(sheetname "")
			)
			(fill
				(thermal_gap 0.5)
				(thermal_bridge_width 0.5)
				(island_removal_mode 0)
			)
			(polygon
				(pts
					(xy 162.941 -82.042) (xy 162.941 -81.534) (xy 163.322 -81.534) (xy 163.322 -82.042)
				)
			)
		)
		(zone
			(layer "B.Cu")
			(hatch none 0.5)
			(connect_pads
				(clearance 0)
			)
			(min_thickness 0.25)
			(keepout
				(tracks not_allowed)
				(vias allowed)
				(pads allowed)
				(copperpour not_allowed)
				(footprints allowed)
			)
			(placement
				(enabled no)
				(sheetname "")
			)
			(fill
				(thermal_gap 0.5)
				(thermal_bridge_width 0.5)
				(island_removal_mode 0)
			)
			(polygon
				(pts
					(xy 163.322 -82.042) (xy 163.322 -81.534) (xy 162.941 -81.534) (xy 162.941 -82.042)
				)
			)
		)
	)
	(footprint ""
		(layer "B.Cu")
		(at 108.9025 -164.973 -90)
		(property "Reference" "T1D5"
			(at 0 0 90)
			(layer "B.SilkS")
			(hide yes)
			(effects
				(font
					(size 1.27 1.27)
				)
				(justify mirror)
			)
		)
		(property "Value" "*"
			(at 3.4036 -4.46405 270)
			(unlocked yes)
			(layer "B.Fab")
			(hide yes)
			(effects
				(font
					(size 0.889 0.889)
					(thickness 0.1524)
				)
				(justify mirror)
			)
		)
		(property "Device Type" "TEST-PAD-12P-1-GP-U_DISCRET-GBA"
			(at 3.4036 -5.98805 270)
			(unlocked yes)
			(layer "B.Fab")
			(hide yes)
			(effects
				(font
					(size 0.889 0.889)
					(thickness 0.1524)
				)
				(justify mirror)
			)
		)
		(duplicate_pad_numbers_are_jumpers no)
		(fp_line
			(start -2.3622 3.4798)
			(end 2.3876 3.4798)
			(stroke
				(width 0.1524)
				(type default)
			)
			(layer "B.SilkS")
		)
		(fp_line
			(start 2.3876 3.4798)
			(end 2.3876 -4.826)
			(stroke
				(width 0.1524)
				(type default)
			)
			(layer "B.SilkS")
		)
		(fp_line
			(start -2.3622 -4.826)
			(end -2.3622 3.4798)
			(stroke
				(width 0.1524)
				(type default)
			)
			(layer "B.SilkS")
		)
		(fp_line
			(start 2.3876 -4.826)
			(end -2.3622 -4.826)
			(stroke
				(width 0.1524)
				(type default)
			)
			(layer "B.SilkS")
		)
		(fp_rect
			(start 2.6416 3.7338)
			(end -2.6162 -5.08)
			(stroke
				(width 0)
				(type default)
			)
			(fill no)
			(layer "B.CrtYd")
		)
		(fp_rect
			(start 2.6416 3.7338)
			(end -2.6162 -5.08)
			(stroke
				(width 0)
				(type default)
			)
			(fill no)
			(layer "B.Fab")
		)
		(pad "1" smd circle
			(at -0.496824 -1.301496 90)
			(size 0.6604 0.6604)
			(layers "B.Cu" "B.Mask" "B.Paste")
			(net "L5_85OHM_5INCH_DP")
		)
		(pad "2" smd circle
			(at 0.503936 -1.301496 90)
			(size 0.6604 0.6604)
			(layers "B.Cu" "B.Mask" "B.Paste")
			(net "L5_85OHM_5INCH_DN")
		)
		(pad "3" smd custom
			(at 0.00889 0.370078 90)
			(size 0.74295 0.74295)
			(layers "B.Cu" "B.Mask" "B.Paste")
			(net "GND")
			(options
				(clearance outline)
				(anchor circle)
			)
			(primitives
				(gr_poly
					(pts
						(xy -2.1209 -1.4859) (xy 2.1209 -1.4859) (xy 2.1209 1.4859) (xy 1.08585 1.4859) (xy 1.08585 0.4699)
						(xy -1.08585 0.4699) (xy -1.08585 1.4859) (xy -2.1209 1.4859)
					)
					(width 0)
					(fill yes)
				)
			)
		)
		(pad "4" thru_hole circle
			(at -1.266444 -3.851656 90)
			(size 1.4478 1.4478)
			(drill 1.0414)
			(layers "*.Cu" "*.Mask")
			(remove_unused_layers no)
			(net "GND")
			(clearance 0.1524)
			(thermal_gap 0.1524)
		)
		(pad "5" thru_hole circle
			(at 1.273556 -3.851656 90)
			(size 1.4478 1.4478)
			(drill 1.0414)
			(layers "*.Cu" "*.Mask")
			(remove_unused_layers no)
			(net "GND")
			(clearance 0.1524)
			(thermal_gap 0.1524)
		)
		(pad "6" thru_hole circle
			(at -1.266444 2.498344 90)
			(size 1.4478 1.4478)
			(drill 1.0414)
			(layers "*.Cu" "*.Mask")
			(remove_unused_layers no)
			(net "GND")
			(clearance 0.1524)
			(thermal_gap 0.1524)
		)
		(pad "7" thru_hole circle
			(at 1.273556 2.498344 90)
			(size 1.4478 1.4478)
			(drill 1.0414)
			(layers "*.Cu" "*.Mask")
			(remove_unused_layers no)
			(net "GND")
			(clearance 0.1524)
			(thermal_gap 0.1524)
		)
		(pad "8" thru_hole circle
			(at -1.27 -0.4572 90)
			(size 0.7112 0.7112)
			(drill 0.4064)
			(layers "*.Cu" "*.Mask")
			(remove_unused_layers no)
			(net "GND")
			(clearance 0.1016)
			(thermal_gap 0.1016)
		)
		(pad "9" thru_hole circle
			(at -1.27 0.762 90)
			(size 0.7112 0.7112)
			(drill 0.4064)
			(layers "*.Cu" "*.Mask")
			(remove_unused_layers no)
			(net "GND")
			(clearance 0.1016)
			(thermal_gap 0.1016)
		)
		(pad "10" thru_hole circle
			(at 0.0254 0.762 90)
			(size 0.7112 0.7112)
			(drill 0.4064)
			(layers "*.Cu" "*.Mask")
			(remove_unused_layers no)
			(net "GND")
			(clearance 0.1016)
			(thermal_gap 0.1016)
		)
		(pad "11" thru_hole circle
			(at 1.27 0.762 90)
			(size 0.7112 0.7112)
			(drill 0.4064)
			(layers "*.Cu" "*.Mask")
			(remove_unused_layers no)
			(net "GND")
			(clearance 0.1016)
			(thermal_gap 0.1016)
		)
		(pad "12" thru_hole circle
			(at 1.27 -0.4572 90)
			(size 0.7112 0.7112)
			(drill 0.4064)
			(layers "*.Cu" "*.Mask")
			(remove_unused_layers no)
			(net "GND")
			(clearance 0.1016)
			(thermal_gap 0.1016)
		)
	)
	(footprint ""
		(layer "B.Cu")
		(at 88.392 -12.954 90)
		(property "Reference" "C5G82"
			(at -1.14681 0.76708 180)
			(unlocked yes)
			(layer "B.SilkS")
			(effects
				(font
					(size 0.7874 0.5842)
					(thickness 0.1524)
				)
				(justify mirror)
			)
		)
		(property "Value" ""
			(at 0 0 90)
			(layer "B.Fab")
			(effects
				(font
					(size 1.27 1.27)
				)
				(justify mirror)
			)
		)
		(duplicate_pad_numbers_are_jumpers no)
		(fp_rect
			(start -0.4953 -0.2032)
			(end 0.4953 1.6002)
			(stroke
				(width 0)
				(type default)
			)
			(fill no)
			(layer "B.CrtYd")
		)
		(fp_line
			(start 0.4953 -0.2032)
			(end -0.4953 -0.2032)
			(stroke
				(width 0.1)
				(type default)
			)
			(layer "B.Fab")
		)
		(fp_line
			(start -0.4953 -0.2032)
			(end -0.4953 1.6002)
			(stroke
				(width 0.1)
				(type default)
			)
			(layer "B.Fab")
		)
		(fp_line
			(start 0.4953 1.6002)
			(end 0.4953 -0.2032)
			(stroke
				(width 0.1)
				(type default)
			)
			(layer "B.Fab")
		)
		(fp_line
			(start -0.4953 1.6002)
			(end 0.4953 1.6002)
			(stroke
				(width 0.1)
				(type default)
			)
			(layer "B.Fab")
		)
		(pad "1" smd rect
			(at 0 0 270)
			(size 0.762 0.889)
			(layers "B.Cu" "B.Mask" "B.Paste")
			(net "PVDDQ_GHJ")
		)
		(pad "2" smd rect
			(at 0 1.397 270)
			(size 0.762 0.889)
			(layers "B.Cu" "B.Mask" "B.Paste")
			(net "GND")
		)
		(zone
			(layer "B.Cu")
			(hatch none 0.5)
			(connect_pads
				(clearance 0)
			)
			(min_thickness 0.25)
			(keepout
				(tracks not_allowed)
				(vias allowed)
				(pads allowed)
				(copperpour not_allowed)
				(footprints allowed)
			)
			(placement
				(enabled no)
				(sheetname "")
			)
			(fill
				(thermal_gap 0.5)
				(thermal_bridge_width 0.5)
				(island_removal_mode 0)
			)
			(polygon
				(pts
					(xy 88.8365 -12.573) (xy 89.3445 -12.573) (xy 89.3445 -13.335) (xy 88.8365 -13.335)
				)
			)
		)
	)
	(footprint ""
		(layer "B.Cu")
		(at 32.832802 -68.101464 90)
		(property "Reference" "C9P22"
			(at 0 0 90)
			(layer "B.SilkS")
			(hide yes)
			(effects
				(font
					(size 1.27 1.27)
				)
				(justify mirror)
			)
		)
		(property "Value" ""
			(at 0 0 90)
			(layer "B.Fab")
			(effects
				(font
					(size 1.27 1.27)
				)
				(justify mirror)
			)
		)
		(duplicate_pad_numbers_are_jumpers no)
		(fp_poly
			(pts
				(xy 0.7239 -0.2159) (xy -0.7239 -0.2159) (xy -0.7239 1.9939) (xy 0.7239 1.9939)
			)
			(stroke
				(width 0)
				(type default)
			)
			(fill no)
			(layer "B.CrtYd")
		)
		(fp_line
			(start 0.7239 -0.2159)
			(end 0.7239 1.9939)
			(stroke
				(width 0.1)
				(type default)
			)
			(layer "B.Fab")
		)
		(fp_line
			(start -0.7239 -0.2159)
			(end 0.7239 -0.2159)
			(stroke
				(width 0.1)
				(type default)
			)
			(layer "B.Fab")
		)
		(fp_line
			(start 0.7239 1.9939)
			(end -0.7239 1.9939)
			(stroke
				(width 0.1)
				(type default)
			)
			(layer "B.Fab")
		)
		(fp_line
			(start -0.7239 1.9939)
			(end -0.7239 -0.2159)
			(stroke
				(width 0.1)
				(type default)
			)
			(layer "B.Fab")
		)
		(pad "1" smd rect
			(at 0 0 270)
			(size 1.27 1.016)
			(layers "B.Cu" "B.Mask" "B.Paste")
			(net "VR_FET_SW_P12V_STBY_PVCCIN_CPU1")
		)
		(pad "2" smd rect
			(at 0 1.778 270)
			(size 1.27 1.016)
			(layers "B.Cu" "B.Mask" "B.Paste")
			(net "GND")
		)
		(zone
			(layer "B.Cu")
			(hatch none 0.5)
			(connect_pads
				(clearance 0)
			)
			(min_thickness 0.25)
			(keepout
				(tracks not_allowed)
				(vias allowed)
				(pads allowed)
				(copperpour not_allowed)
				(footprints allowed)
			)
			(placement
				(enabled no)
				(sheetname "")
			)
			(fill
				(thermal_gap 0.5)
				(thermal_bridge_width 0.5)
				(island_removal_mode 0)
			)
			(polygon
				(pts
					(xy 33.340802 -68.736464) (xy 33.340802 -67.466464) (xy 34.102802 -67.466464) (xy 34.102802 -68.736464)
				)
			)
		)
	)
	(footprint ""
		(layer "B.Cu")
		(at 400.756628 -115.579144)
		(property "Reference" "R24W2"
			(at 0.8382 -0.67818 0)
			(unlocked yes)
			(layer "B.SilkS")
			(effects
				(font
					(size 0.4064 0.254)
					(thickness 0.1524)
				)
				(justify left mirror)
			)
		)
		(property "Value" ""
			(at 0 0 0)
			(layer "B.Fab")
			(effects
				(font
					(size 1.27 1.27)
				)
				(justify mirror)
			)
		)
		(duplicate_pad_numbers_are_jumpers no)
		(fp_poly
			(pts
				(xy 0.2794 -0.1016) (xy -0.2794 -0.1016) (xy -0.2794 0.9906) (xy 0.2794 0.9906)
			)
			(stroke
				(width 0)
				(type default)
			)
			(fill no)
			(layer "B.CrtYd")
		)
		(fp_line
			(start -0.2794 -0.1016)
			(end 0.2794 -0.1016)
			(stroke
				(width 0.1)
				(type default)
			)
			(layer "B.Fab")
		)
		(fp_line
			(start -0.2794 0.9906)
			(end -0.2794 -0.1016)
			(stroke
				(width 0.1)
				(type default)
			)
			(layer "B.Fab")
		)
		(fp_line
			(start 0.2794 -0.1016)
			(end 0.2794 0.9906)
			(stroke
				(width 0.1)
				(type default)
			)
			(layer "B.Fab")
		)
		(fp_line
			(start 0.2794 0.9906)
			(end -0.2794 0.9906)
			(stroke
				(width 0.1)
				(type default)
			)
			(layer "B.Fab")
		)
		(pad "1" smd rect
			(at 0 0 180)
			(size 0.508 0.508)
			(layers "B.Cu" "B.Mask" "B.Paste")
			(net "P3V3_STBY")
		)
		(pad "2" smd rect
			(at 0 0.889 180)
			(size 0.508 0.508)
			(layers "B.Cu" "B.Mask" "B.Paste")
			(net "SMB_SLOTX24_PCH_STBY_LVC3_SCL")
		)
		(zone
			(layer "B.Cu")
			(hatch none 0.5)
			(connect_pads
				(clearance 0)
			)
			(min_thickness 0.25)
			(keepout
				(tracks allowed)
				(vias not_allowed)
				(pads allowed)
				(copperpour not_allowed)
				(footprints allowed)
			)
			(placement
				(enabled no)
				(sheetname "")
			)
			(fill
				(thermal_gap 0.5)
				(thermal_bridge_width 0.5)
				(island_removal_mode 0)
			)
			(polygon
				(pts
					(xy 401.010628 -115.325144) (xy 400.502628 -115.325144) (xy 400.502628 -114.944144) (xy 401.010628 -114.944144)
				)
			)
		)
		(zone
			(layer "B.Cu")
			(hatch none 0.5)
			(connect_pads
				(clearance 0)
			)
			(min_thickness 0.25)
			(keepout
				(tracks not_allowed)
				(vias allowed)
				(pads allowed)
				(copperpour not_allowed)
				(footprints allowed)
			)
			(placement
				(enabled no)
				(sheetname "")
			)
			(fill
				(thermal_gap 0.5)
				(thermal_bridge_width 0.5)
				(island_removal_mode 0)
			)
			(polygon
				(pts
					(xy 401.010628 -114.944144) (xy 400.502628 -114.944144) (xy 400.502628 -115.325144) (xy 401.010628 -115.325144)
				)
			)
		)
	)
	(footprint ""
		(layer "B.Cu")
		(at 334.743806 -61.257434)
		(property "Reference" "C2U4"
			(at 0 0 0)
			(layer "B.SilkS")
			(hide yes)
			(effects
				(font
					(size 1.27 1.27)
				)
				(justify mirror)
			)
		)
		(property "Value" ""
			(at 0 0 0)
			(layer "B.Fab")
			(effects
				(font
					(size 1.27 1.27)
				)
				(justify mirror)
			)
		)
		(duplicate_pad_numbers_are_jumpers no)
		(fp_poly
			(pts
				(xy -0.3048 -0.1016) (xy -0.3048 0.9906) (xy 0.3048 0.9906) (xy 0.3048 -0.1016)
			)
			(stroke
				(width 0)
				(type default)
			)
			(fill no)
			(layer "B.CrtYd")
		)
		(fp_line
			(start -0.3048 -0.1016)
			(end 0.3048 -0.1016)
			(stroke
				(width 0.1)
				(type default)
			)
			(layer "B.Fab")
		)
		(fp_line
			(start -0.3048 0.9906)
			(end -0.3048 -0.1016)
			(stroke
				(width 0.1)
				(type default)
			)
			(layer "B.Fab")
		)
		(fp_line
			(start 0.3048 -0.1016)
			(end 0.3048 0.9906)
			(stroke
				(width 0.1)
				(type default)
			)
			(layer "B.Fab")
		)
		(fp_line
			(start 0.3048 0.9906)
			(end -0.3048 0.9906)
			(stroke
				(width 0.1)
				(type default)
			)
			(layer "B.Fab")
		)
		(pad "1" smd rect
			(at 0 0 180)
			(size 0.508 0.508)
			(layers "B.Cu" "B.Mask" "B.Paste")
			(net "P3E_CPU0_PE1_PCH_RXN<0>")
		)
		(pad "2" smd rect
			(at 0 0.889 180)
			(size 0.508 0.508)
			(layers "B.Cu" "B.Mask" "B.Paste")
			(net "P3E_CPU0_PE1_SS_RXN<0>")
		)
		(zone
			(layer "B.Cu")
			(hatch none 0.5)
			(connect_pads
				(clearance 0)
			)
			(min_thickness 0.25)
			(keepout
				(tracks allowed)
				(vias not_allowed)
				(pads allowed)
				(copperpour not_allowed)
				(footprints allowed)
			)
			(placement
				(enabled no)
				(sheetname "")
			)
			(fill
				(thermal_gap 0.5)
				(thermal_bridge_width 0.5)
				(island_removal_mode 0)
			)
			(polygon
				(pts
					(xy 334.997806 -61.003434) (xy 334.489806 -61.003434) (xy 334.489806 -60.622434) (xy 334.997806 -60.622434)
				)
			)
		)
		(zone
			(layer "B.Cu")
			(hatch none 0.5)
			(connect_pads
				(clearance 0)
			)
			(min_thickness 0.25)
			(keepout
				(tracks not_allowed)
				(vias allowed)
				(pads allowed)
				(copperpour not_allowed)
				(footprints allowed)
			)
			(placement
				(enabled no)
				(sheetname "")
			)
			(fill
				(thermal_gap 0.5)
				(thermal_bridge_width 0.5)
				(island_removal_mode 0)
			)
			(polygon
				(pts
					(xy 334.997806 -60.622434) (xy 334.489806 -60.622434) (xy 334.489806 -61.003434) (xy 334.997806 -61.003434)
				)
			)
		)
	)
	(footprint ""
		(layer "B.Cu")
		(at 443.865 -116.49202)
		(property "Reference" "C2M14"
			(at 0 0 0)
			(layer "B.SilkS")
			(hide yes)
			(effects
				(font
					(size 1.27 1.27)
				)
				(justify mirror)
			)
		)
		(property "Value" ""
			(at 0 0 0)
			(layer "B.Fab")
			(effects
				(font
					(size 1.27 1.27)
				)
				(justify mirror)
			)
		)
		(duplicate_pad_numbers_are_jumpers no)
		(fp_rect
			(start -0.3048 0.9906)
			(end 0.3048 -0.1016)
			(stroke
				(width 0)
				(type default)
			)
			(fill no)
			(layer "B.CrtYd")
		)
		(fp_line
			(start -0.3048 -0.1016)
			(end 0.3048 -0.1016)
			(stroke
				(width 0.1)
				(type default)
			)
			(layer "B.Fab")
		)
		(fp_line
			(start -0.3048 0.9906)
			(end -0.3048 -0.1016)
			(stroke
				(width 0.1)
				(type default)
			)
			(layer "B.Fab")
		)
		(fp_line
			(start 0.3048 -0.1016)
			(end 0.3048 0.9906)
			(stroke
				(width 0.1)
				(type default)
			)
			(layer "B.Fab")
		)
		(fp_line
			(start 0.3048 0.9906)
			(end -0.3048 0.9906)
			(stroke
				(width 0.1)
				(type default)
			)
			(layer "B.Fab")
		)
		(pad "1" smd rect
			(at 0 0 180)
			(size 0.508 0.508)
			(layers "B.Cu" "B.Mask" "B.Paste")
			(net "P3E_CPU0_PE3_OCP_TXP<8>")
		)
		(pad "2" smd rect
			(at 0 0.889 180)
			(size 0.508 0.508)
			(layers "B.Cu" "B.Mask" "B.Paste")
			(net "P3E_OCP_CPU0_PE3_C_TXP<8>")
		)
		(zone
			(layer "B.Cu")
			(hatch none 0.5)
			(connect_pads
				(clearance 0)
			)
			(min_thickness 0.25)
			(keepout
				(tracks not_allowed)
				(vias allowed)
				(pads allowed)
				(copperpour not_allowed)
				(footprints allowed)
			)
			(placement
				(enabled no)
				(sheetname "")
			)
			(fill
				(thermal_gap 0.5)
				(thermal_bridge_width 0.5)
				(island_removal_mode 0)
			)
			(polygon
				(pts
					(xy 443.611 -115.85702) (xy 444.119 -115.85702) (xy 444.119 -116.23802) (xy 443.611 -116.23802)
				)
			)
		)
		(zone
			(layer "B.Cu")
			(hatch none 0.5)
			(connect_pads
				(clearance 0)
			)
			(min_thickness 0.25)
			(keepout
				(tracks allowed)
				(vias not_allowed)
				(pads allowed)
				(copperpour not_allowed)
				(footprints allowed)
			)
			(placement
				(enabled no)
				(sheetname "")
			)
			(fill
				(thermal_gap 0.5)
				(thermal_bridge_width 0.5)
				(island_removal_mode 0)
			)
			(polygon
				(pts
					(xy 443.611 -115.85702) (xy 444.119 -115.85702) (xy 444.119 -116.23802) (xy 443.611 -116.23802)
				)
			)
		)
	)
)
